(kicad_pcb
	(version 20260206)
	(generator "pcbnew")
	(generator_version "10.0")
	(general
		(thickness 1.6)
		(legacy_teardrops no)
	)
	(paper "A4")
	(title_block
		(title "12092022_DA0F0TFB6D0_F0T_FAN_BOARD_MP5048_D_brd_v02_OCP.brd")
		(comment 1 "Grand Teton / footprints 597-602 of 924")
	)
	(layers
		(0 "F.Cu" signal "TOP")
		(4 "In1.Cu" signal "GND")
		(6 "In2.Cu" signal "IN1")
		(8 "In3.Cu" signal "IN2")
		(10 "In4.Cu" signal "GND1")
		(2 "B.Cu" signal "BOTTOM")
		(9 "F.Adhes" user "F.Adhesive")
		(11 "B.Adhes" user "B.Adhesive")
		(13 "F.Paste" user "Package Geometry/Pastemask Top")
		(15 "B.Paste" user "Package Geometry/Pastemask Bottom")
		(5 "F.SilkS" user "Ref Des/Silkscreen Top")
		(7 "B.SilkS" user "Ref Des/Silkscreen Bottom")
		(1 "F.Mask" user "Board Geometry/Soldermask Top")
		(3 "B.Mask" user "Board Geometry/Soldermask Bottom")
		(17 "Dwgs.User" user "User.Drawings")
		(19 "Cmts.User" user "User.Comments")
		(21 "Eco1.User" user "User.Eco1")
		(23 "Eco2.User" user "User.Eco2")
		(25 "Edge.Cuts" user "Board Geometry/Outline")
		(27 "Margin" user)
		(31 "F.CrtYd" user "Package Geometry/Place Bound Top")
		(29 "B.CrtYd" user "Package Geometry/Place Bound Bottom")
		(35 "F.Fab" user "Ref Des/Assembly Top")
		(33 "B.Fab" user "Ref Des/Assembly Bottom")
	)
	(footprint ""
		(layer "F.Cu")
		(at 17.018 -24.892 180)
		(property "Reference" "R5540"
			(at 0 0 180)
			(layer "F.SilkS")
			(hide yes)
			(effects
				(font
					(size 1.27 1.27)
				)
			)
		)
		(property "Value" ""
			(at 0 0 180)
			(layer "F.Fab")
			(effects
				(font
					(size 1.27 1.27)
				)
			)
		)
		(duplicate_pad_numbers_are_jumpers no)
		(fp_line
			(start 0.7874 0.4064)
			(end -0.7874 0.4064)
			(stroke
				(width 0.1524)
				(type default)
			)
			(layer "F.SilkS")
		)
		(fp_line
			(start 0.7874 -0.4064)
			(end 0.7874 0.4064)
			(stroke
				(width 0.1524)
				(type default)
			)
			(layer "F.SilkS")
		)
		(fp_line
			(start -0.7874 0.4064)
			(end -0.7874 -0.4064)
			(stroke
				(width 0.1524)
				(type default)
			)
			(layer "F.SilkS")
		)
		(fp_line
			(start -0.7874 -0.4064)
			(end 0.7874 -0.4064)
			(stroke
				(width 0.1524)
				(type default)
			)
			(layer "F.SilkS")
		)
		(fp_line
			(start 0.67945 0.3048)
			(end 0.120396 0.3048)
			(stroke
				(width 0.1)
				(type default)
			)
			(layer "F.Fab")
		)
		(fp_line
			(start 0.67945 -0.3048)
			(end 0.67945 0.3048)
			(stroke
				(width 0.1)
				(type default)
			)
			(layer "F.Fab")
		)
		(fp_line
			(start 0.12065 -0.2794)
			(end 0.12065 -0.3048)
			(stroke
				(width 0.1)
				(type default)
			)
			(layer "F.Fab")
		)
		(fp_line
			(start 0.12065 -0.3048)
			(end 0.67945 -0.3048)
			(stroke
				(width 0.1)
				(type default)
			)
			(layer "F.Fab")
		)
		(fp_line
			(start 0.120396 0.3048)
			(end 0.120396 0.2794)
			(stroke
				(width 0.1)
				(type default)
			)
			(layer "F.Fab")
		)
		(fp_line
			(start 0.120396 0.2794)
			(end -0.12065 0.2794)
			(stroke
				(width 0.1)
				(type default)
			)
			(layer "F.Fab")
		)
		(fp_line
			(start -0.12065 0.3048)
			(end -0.67945 0.3048)
			(stroke
				(width 0.1)
				(type default)
			)
			(layer "F.Fab")
		)
		(fp_line
			(start -0.12065 0.2794)
			(end -0.12065 0.3048)
			(stroke
				(width 0.1)
				(type default)
			)
			(layer "F.Fab")
		)
		(fp_line
			(start -0.12065 -0.2794)
			(end 0.12065 -0.2794)
			(stroke
				(width 0.1)
				(type default)
			)
			(layer "F.Fab")
		)
		(fp_line
			(start -0.12065 -0.305054)
			(end -0.12065 -0.2794)
			(stroke
				(width 0.1)
				(type default)
			)
			(layer "F.Fab")
		)
		(fp_line
			(start -0.67945 0.3048)
			(end -0.67945 -0.305054)
			(stroke
				(width 0.1)
				(type default)
			)
			(layer "F.Fab")
		)
		(fp_line
			(start -0.67945 -0.305054)
			(end -0.12065 -0.305054)
			(stroke
				(width 0.1)
				(type default)
			)
			(layer "F.Fab")
		)
		(pad "1" smd rect
			(at -0.40005 0)
			(size 0.4572 0.508)
			(layers "F.Cu" "F.Mask" "F.Paste")
			(net "P12V_LED_FAN4")
		)
		(pad "2" smd rect
			(at 0.40005 0)
			(size 0.4572 0.508)
			(layers "F.Cu" "F.Mask" "F.Paste")
			(net "FAN_4_OK_LED_R_N")
		)
	)
	(footprint ""
		(layer "F.Cu")
		(at 15.621 -162.814)
		(property "Reference" "C52"
			(at 0 0 0)
			(layer "F.SilkS")
			(hide yes)
			(effects
				(font
					(size 1.27 1.27)
				)
			)
		)
		(property "Value" ""
			(at 0 0 0)
			(layer "F.Fab")
			(effects
				(font
					(size 1.27 1.27)
				)
			)
		)
		(duplicate_pad_numbers_are_jumpers no)
		(fp_line
			(start -0.7874 -0.4064)
			(end 0.7874 -0.4064)
			(stroke
				(width 0.1524)
				(type default)
			)
			(layer "F.SilkS")
		)
		(fp_line
			(start -0.7874 0.4064)
			(end -0.7874 -0.4064)
			(stroke
				(width 0.1524)
				(type default)
			)
			(layer "F.SilkS")
		)
		(fp_line
			(start 0.7874 -0.4064)
			(end 0.7874 0.4064)
			(stroke
				(width 0.1524)
				(type default)
			)
			(layer "F.SilkS")
		)
		(fp_line
			(start 0.7874 0.4064)
			(end -0.7874 0.4064)
			(stroke
				(width 0.1524)
				(type default)
			)
			(layer "F.SilkS")
		)
		(fp_line
			(start -0.67945 -0.305054)
			(end -0.12065 -0.305054)
			(stroke
				(width 0.1)
				(type default)
			)
			(layer "F.Fab")
		)
		(fp_line
			(start -0.67945 0.3048)
			(end -0.67945 -0.305054)
			(stroke
				(width 0.1)
				(type default)
			)
			(layer "F.Fab")
		)
		(fp_line
			(start -0.12065 -0.305054)
			(end -0.12065 -0.2794)
			(stroke
				(width 0.1)
				(type default)
			)
			(layer "F.Fab")
		)
		(fp_line
			(start -0.12065 -0.2794)
			(end 0.12065 -0.2794)
			(stroke
				(width 0.1)
				(type default)
			)
			(layer "F.Fab")
		)
		(fp_line
			(start -0.12065 0.2794)
			(end -0.12065 0.3048)
			(stroke
				(width 0.1)
				(type default)
			)
			(layer "F.Fab")
		)
		(fp_line
			(start -0.12065 0.3048)
			(end -0.67945 0.3048)
			(stroke
				(width 0.1)
				(type default)
			)
			(layer "F.Fab")
		)
		(fp_line
			(start 0.120396 0.2794)
			(end -0.12065 0.2794)
			(stroke
				(width 0.1)
				(type default)
			)
			(layer "F.Fab")
		)
		(fp_line
			(start 0.120396 0.3048)
			(end 0.120396 0.2794)
			(stroke
				(width 0.1)
				(type default)
			)
			(layer "F.Fab")
		)
		(fp_line
			(start 0.12065 -0.3048)
			(end 0.67945 -0.3048)
			(stroke
				(width 0.1)
				(type default)
			)
			(layer "F.Fab")
		)
		(fp_line
			(start 0.12065 -0.2794)
			(end 0.12065 -0.3048)
			(stroke
				(width 0.1)
				(type default)
			)
			(layer "F.Fab")
		)
		(fp_line
			(start 0.67945 -0.3048)
			(end 0.67945 0.3048)
			(stroke
				(width 0.1)
				(type default)
			)
			(layer "F.Fab")
		)
		(fp_line
			(start 0.67945 0.3048)
			(end 0.120396 0.3048)
			(stroke
				(width 0.1)
				(type default)
			)
			(layer "F.Fab")
		)
		(pad "1" smd circle
			(at -0.40005 0)
			(size 0 0)
			(layers "F.Cu" "F.Mask" "F.Paste")
			(net "FAN_0_PRESENT_N")
		)
		(pad "2" smd circle
			(at 0.40005 0)
			(size 0 0)
			(layers "F.Cu" "F.Mask" "F.Paste")
			(net "GND")
		)
	)
	(footprint ""
		(layer "F.Cu")
		(at 14.859 -131.064)
		(property "Reference" "R5616"
			(at 0 0 0)
			(layer "F.SilkS")
			(hide yes)
			(effects
				(font
					(size 1.27 1.27)
				)
			)
		)
		(property "Value" ""
			(at 0 0 0)
			(layer "F.Fab")
			(effects
				(font
					(size 1.27 1.27)
				)
			)
		)
		(duplicate_pad_numbers_are_jumpers no)
		(fp_line
			(start -0.7874 -0.4064)
			(end 0.7874 -0.4064)
			(stroke
				(width 0.1524)
				(type default)
			)
			(layer "F.SilkS")
		)
		(fp_line
			(start -0.7874 0.4064)
			(end -0.7874 -0.4064)
			(stroke
				(width 0.1524)
				(type default)
			)
			(layer "F.SilkS")
		)
		(fp_line
			(start 0.7874 -0.4064)
			(end 0.7874 0.4064)
			(stroke
				(width 0.1524)
				(type default)
			)
			(layer "F.SilkS")
		)
		(fp_line
			(start 0.7874 0.4064)
			(end -0.7874 0.4064)
			(stroke
				(width 0.1524)
				(type default)
			)
			(layer "F.SilkS")
		)
		(fp_line
			(start -0.67945 -0.305054)
			(end -0.12065 -0.305054)
			(stroke
				(width 0.1)
				(type default)
			)
			(layer "F.Fab")
		)
		(fp_line
			(start -0.67945 0.3048)
			(end -0.67945 -0.305054)
			(stroke
				(width 0.1)
				(type default)
			)
			(layer "F.Fab")
		)
		(fp_line
			(start -0.12065 -0.305054)
			(end -0.12065 -0.2794)
			(stroke
				(width 0.1)
				(type default)
			)
			(layer "F.Fab")
		)
		(fp_line
			(start -0.12065 -0.2794)
			(end 0.12065 -0.2794)
			(stroke
				(width 0.1)
				(type default)
			)
			(layer "F.Fab")
		)
		(fp_line
			(start -0.12065 0.2794)
			(end -0.12065 0.3048)
			(stroke
				(width 0.1)
				(type default)
			)
			(layer "F.Fab")
		)
		(fp_line
			(start -0.12065 0.3048)
			(end -0.67945 0.3048)
			(stroke
				(width 0.1)
				(type default)
			)
			(layer "F.Fab")
		)
		(fp_line
			(start 0.120396 0.2794)
			(end -0.12065 0.2794)
			(stroke
				(width 0.1)
				(type default)
			)
			(layer "F.Fab")
		)
		(fp_line
			(start 0.120396 0.3048)
			(end 0.120396 0.2794)
			(stroke
				(width 0.1)
				(type default)
			)
			(layer "F.Fab")
		)
		(fp_line
			(start 0.12065 -0.3048)
			(end 0.67945 -0.3048)
			(stroke
				(width 0.1)
				(type default)
			)
			(layer "F.Fab")
		)
		(fp_line
			(start 0.12065 -0.2794)
			(end 0.12065 -0.3048)
			(stroke
				(width 0.1)
				(type default)
			)
			(layer "F.Fab")
		)
		(fp_line
			(start 0.67945 -0.3048)
			(end 0.67945 0.3048)
			(stroke
				(width 0.1)
				(type default)
			)
			(layer "F.Fab")
		)
		(fp_line
			(start 0.67945 0.3048)
			(end 0.120396 0.3048)
			(stroke
				(width 0.1)
				(type default)
			)
			(layer "F.Fab")
		)
		(pad "1" smd rect
			(at -0.40005 0 180)
			(size 0.4572 0.508)
			(layers "F.Cu" "F.Mask" "F.Paste")
			(net "FAN_6_TACH_IL")
		)
		(pad "2" smd rect
			(at 0.40005 0 180)
			(size 0.4572 0.508)
			(layers "F.Cu" "F.Mask" "F.Paste")
			(net "FAN_6_TACH_IL_R1")
		)
	)
	(footprint ""
		(layer "F.Cu")
		(at 42.291 -137.287 -90)
		(property "Reference" "R5564"
			(at 0 0 270)
			(layer "F.SilkS")
			(hide yes)
			(effects
				(font
					(size 1.27 1.27)
				)
			)
		)
		(property "Value" ""
			(at 0 0 270)
			(layer "F.Fab")
			(effects
				(font
					(size 1.27 1.27)
				)
			)
		)
		(duplicate_pad_numbers_are_jumpers no)
		(fp_line
			(start -0.7874 0.4064)
			(end -0.7874 -0.4064)
			(stroke
				(width 0.1524)
				(type default)
			)
			(layer "F.SilkS")
		)
		(fp_line
			(start 0.7874 0.4064)
			(end -0.7874 0.4064)
			(stroke
				(width 0.1524)
				(type default)
			)
			(layer "F.SilkS")
		)
		(fp_line
			(start -0.7874 -0.4064)
			(end 0.7874 -0.4064)
			(stroke
				(width 0.1524)
				(type default)
			)
			(layer "F.SilkS")
		)
		(fp_line
			(start 0.7874 -0.4064)
			(end 0.7874 0.4064)
			(stroke
				(width 0.1524)
				(type default)
			)
			(layer "F.SilkS")
		)
		(fp_line
			(start -0.67945 0.3048)
			(end -0.67945 -0.305054)
			(stroke
				(width 0.1)
				(type default)
			)
			(layer "F.Fab")
		)
		(fp_line
			(start -0.12065 0.3048)
			(end -0.67945 0.3048)
			(stroke
				(width 0.1)
				(type default)
			)
			(layer "F.Fab")
		)
		(fp_line
			(start 0.120396 0.3048)
			(end 0.120396 0.2794)
			(stroke
				(width 0.1)
				(type default)
			)
			(layer "F.Fab")
		)
		(fp_line
			(start 0.67945 0.3048)
			(end 0.120396 0.3048)
			(stroke
				(width 0.1)
				(type default)
			)
			(layer "F.Fab")
		)
		(fp_line
			(start -0.12065 0.2794)
			(end -0.12065 0.3048)
			(stroke
				(width 0.1)
				(type default)
			)
			(layer "F.Fab")
		)
		(fp_line
			(start 0.120396 0.2794)
			(end -0.12065 0.2794)
			(stroke
				(width 0.1)
				(type default)
			)
			(layer "F.Fab")
		)
		(fp_line
			(start -0.12065 -0.2794)
			(end 0.12065 -0.2794)
			(stroke
				(width 0.1)
				(type default)
			)
			(layer "F.Fab")
		)
		(fp_line
			(start 0.12065 -0.2794)
			(end 0.12065 -0.3048)
			(stroke
				(width 0.1)
				(type default)
			)
			(layer "F.Fab")
		)
		(fp_line
			(start 0.12065 -0.3048)
			(end 0.67945 -0.3048)
			(stroke
				(width 0.1)
				(type default)
			)
			(layer "F.Fab")
		)
		(fp_line
			(start 0.67945 -0.3048)
			(end 0.67945 0.3048)
			(stroke
				(width 0.1)
				(type default)
			)
			(layer "F.Fab")
		)
		(fp_line
			(start -0.67945 -0.305054)
			(end -0.12065 -0.305054)
			(stroke
				(width 0.1)
				(type default)
			)
			(layer "F.Fab")
		)
		(fp_line
			(start -0.12065 -0.305054)
			(end -0.12065 -0.2794)
			(stroke
				(width 0.1)
				(type default)
			)
			(layer "F.Fab")
		)
		(pad "1" smd circle
			(at -0.40005 0 270)
			(size 0 0)
			(layers "F.Cu" "F.Mask" "F.Paste")
			(net "GND")
		)
		(pad "2" smd circle
			(at 0.40005 0 270)
			(size 0 0)
			(layers "F.Cu" "F.Mask" "F.Paste")
			(net "U403_ADD2")
		)
	)
	(footprint ""
		(layer "F.Cu")
		(at 25.527 -124.079 180)
		(property "Reference" "R4953"
			(at 0 0 180)
			(layer "F.SilkS")
			(hide yes)
			(effects
				(font
					(size 1.27 1.27)
				)
			)
		)
		(property "Value" ""
			(at 0 0 180)
			(layer "F.Fab")
			(effects
				(font
					(size 1.27 1.27)
				)
			)
		)
		(duplicate_pad_numbers_are_jumpers no)
		(fp_line
			(start 0.7874 0.4064)
			(end -0.7874 0.4064)
			(stroke
				(width 0.1524)
				(type default)
			)
			(layer "F.SilkS")
		)
		(fp_line
			(start 0.7874 -0.4064)
			(end 0.7874 0.4064)
			(stroke
				(width 0.1524)
				(type default)
			)
			(layer "F.SilkS")
		)
		(fp_line
			(start -0.7874 0.4064)
			(end -0.7874 -0.4064)
			(stroke
				(width 0.1524)
				(type default)
			)
			(layer "F.SilkS")
		)
		(fp_line
			(start -0.7874 -0.4064)
			(end 0.7874 -0.4064)
			(stroke
				(width 0.1524)
				(type default)
			)
			(layer "F.SilkS")
		)
		(fp_line
			(start 0.67945 0.3048)
			(end 0.120396 0.3048)
			(stroke
				(width 0.1)
				(type default)
			)
			(layer "F.Fab")
		)
		(fp_line
			(start 0.67945 -0.3048)
			(end 0.67945 0.3048)
			(stroke
				(width 0.1)
				(type default)
			)
			(layer "F.Fab")
		)
		(fp_line
			(start 0.12065 -0.2794)
			(end 0.12065 -0.3048)
			(stroke
				(width 0.1)
				(type default)
			)
			(layer "F.Fab")
		)
		(fp_line
			(start 0.12065 -0.3048)
			(end 0.67945 -0.3048)
			(stroke
				(width 0.1)
				(type default)
			)
			(layer "F.Fab")
		)
		(fp_line
			(start 0.120396 0.3048)
			(end 0.120396 0.2794)
			(stroke
				(width 0.1)
				(type default)
			)
			(layer "F.Fab")
		)
		(fp_line
			(start 0.120396 0.2794)
			(end -0.12065 0.2794)
			(stroke
				(width 0.1)
				(type default)
			)
			(layer "F.Fab")
		)
		(fp_line
			(start -0.12065 0.3048)
			(end -0.67945 0.3048)
			(stroke
				(width 0.1)
				(type default)
			)
			(layer "F.Fab")
		)
		(fp_line
			(start -0.12065 0.2794)
			(end -0.12065 0.3048)
			(stroke
				(width 0.1)
				(type default)
			)
			(layer "F.Fab")
		)
		(fp_line
			(start -0.12065 -0.2794)
			(end 0.12065 -0.2794)
			(stroke
				(width 0.1)
				(type default)
			)
			(layer "F.Fab")
		)
		(fp_line
			(start -0.12065 -0.305054)
			(end -0.12065 -0.2794)
			(stroke
				(width 0.1)
				(type default)
			)
			(layer "F.Fab")
		)
		(fp_line
			(start -0.67945 0.3048)
			(end -0.67945 -0.305054)
			(stroke
				(width 0.1)
				(type default)
			)
			(layer "F.Fab")
		)
		(fp_line
			(start -0.67945 -0.305054)
			(end -0.12065 -0.305054)
			(stroke
				(width 0.1)
				(type default)
			)
			(layer "F.Fab")
		)
		(pad "1" smd circle
			(at -0.40005 0 180)
			(size 0 0)
			(layers "F.Cu" "F.Mask" "F.Paste")
			(net "GND")
		)
		(pad "2" smd circle
			(at 0.40005 0 180)
			(size 0 0)
			(layers "F.Cu" "F.Mask" "F.Paste")
			(net "MAX31790_U330_PWM_START0")
		)
	)
	(footprint ""
		(layer "F.Cu")
		(at 13.335 -167.64 180)
		(property "Reference" "R5510"
			(at 0 0 180)
			(layer "F.SilkS")
			(hide yes)
			(effects
				(font
					(size 1.27 1.27)
				)
			)
		)
		(property "Value" ""
			(at 0 0 180)
			(layer "F.Fab")
			(effects
				(font
					(size 1.27 1.27)
				)
			)
		)
		(duplicate_pad_numbers_are_jumpers no)
		(fp_line
			(start 0.7874 0.4064)
			(end -0.7874 0.4064)
			(stroke
				(width 0.1524)
				(type default)
			)
			(layer "F.SilkS")
		)
		(fp_line
			(start 0.7874 -0.4064)
			(end 0.7874 0.4064)
			(stroke
				(width 0.1524)
				(type default)
			)
			(layer "F.SilkS")
		)
		(fp_line
			(start -0.7874 0.4064)
			(end -0.7874 -0.4064)
			(stroke
				(width 0.1524)
				(type default)
			)
			(layer "F.SilkS")
		)
		(fp_line
			(start -0.7874 -0.4064)
			(end 0.7874 -0.4064)
			(stroke
				(width 0.1524)
				(type default)
			)
			(layer "F.SilkS")
		)
		(fp_line
			(start 0.67945 0.3048)
			(end 0.120396 0.3048)
			(stroke
				(width 0.1)
				(type default)
			)
			(layer "F.Fab")
		)
		(fp_line
			(start 0.67945 -0.3048)
			(end 0.67945 0.3048)
			(stroke
				(width 0.1)
				(type default)
			)
			(layer "F.Fab")
		)
		(fp_line
			(start 0.12065 -0.2794)
			(end 0.12065 -0.3048)
			(stroke
				(width 0.1)
				(type default)
			)
			(layer "F.Fab")
		)
		(fp_line
			(start 0.12065 -0.3048)
			(end 0.67945 -0.3048)
			(stroke
				(width 0.1)
				(type default)
			)
			(layer "F.Fab")
		)
		(fp_line
			(start 0.120396 0.3048)
			(end 0.120396 0.2794)
			(stroke
				(width 0.1)
				(type default)
			)
			(layer "F.Fab")
		)
		(fp_line
			(start 0.120396 0.2794)
			(end -0.12065 0.2794)
			(stroke
				(width 0.1)
				(type default)
			)
			(layer "F.Fab")
		)
		(fp_line
			(start -0.12065 0.3048)
			(end -0.67945 0.3048)
			(stroke
				(width 0.1)
				(type default)
			)
			(layer "F.Fab")
		)
		(fp_line
			(start -0.12065 0.2794)
			(end -0.12065 0.3048)
			(stroke
				(width 0.1)
				(type default)
			)
			(layer "F.Fab")
		)
		(fp_line
			(start -0.12065 -0.2794)
			(end 0.12065 -0.2794)
			(stroke
				(width 0.1)
				(type default)
			)
			(layer "F.Fab")
		)
		(fp_line
			(start -0.12065 -0.305054)
			(end -0.12065 -0.2794)
			(stroke
				(width 0.1)
				(type default)
			)
			(layer "F.Fab")
		)
		(fp_line
			(start -0.67945 0.3048)
			(end -0.67945 -0.305054)
			(stroke
				(width 0.1)
				(type default)
			)
			(layer "F.Fab")
		)
		(fp_line
			(start -0.67945 -0.305054)
			(end -0.12065 -0.305054)
			(stroke
				(width 0.1)
				(type default)
			)
			(layer "F.Fab")
		)
		(pad "1" smd circle
			(at -0.40005 0 180)
			(size 0 0)
			(layers "F.Cu" "F.Mask" "F.Paste")
			(net "P3V3_AUX")
		)
		(pad "2" smd circle
			(at 0.40005 0 180)
			(size 0 0)
			(layers "F.Cu" "F.Mask" "F.Paste")
			(net "FAN_3_PRESENT_N")
		)
	)
)
